(kicad_pcb
	(version 20260206)
	(generator "pcbnew")
	(generator_version "10.0")
	(general
		(thickness 1.6)
		(legacy_teardrops no)
	)
	(paper "A4")
	(title_block
		(title "03242023_DA0F0TMBIJ0_F0T_Motherboard_J_brd_V01_OCP.brd")
		(comment 1 "Grand Teton / footprints 5169-5175 of 6105")
	)
	(layers
		(0 "F.Cu" signal "TOP")
		(4 "In1.Cu" signal "GND")
		(6 "In2.Cu" signal "IN1")
		(8 "In3.Cu" signal "GND1")
		(10 "In4.Cu" signal "IN2")
		(12 "In5.Cu" signal "GND2")
		(14 "In6.Cu" signal "IN3")
		(16 "In7.Cu" signal "GND3")
		(18 "In8.Cu" signal "VCC")
		(20 "In9.Cu" signal "VCC1")
		(22 "In10.Cu" signal "GND4")
		(24 "In11.Cu" signal "IN4")
		(26 "In12.Cu" signal "GND5")
		(28 "In13.Cu" signal "IN5")
		(30 "In14.Cu" signal "GND6")
		(32 "In15.Cu" signal "IN6")
		(34 "In16.Cu" signal "GND7")
		(2 "B.Cu" signal "BOTTOM")
		(9 "F.Adhes" user "F.Adhesive")
		(11 "B.Adhes" user "B.Adhesive")
		(13 "F.Paste" user "Package Geometry/Pastemask Top")
		(15 "B.Paste" user "Package Geometry/Pastemask Bottom")
		(5 "F.SilkS" user "Ref Des/Silkscreen Top")
		(7 "B.SilkS" user "Ref Des/Silkscreen Bottom")
		(1 "F.Mask" user "Board Geometry/Soldermask Top")
		(3 "B.Mask" user "Board Geometry/Soldermask Bottom")
		(17 "Dwgs.User" user "User.Drawings")
		(19 "Cmts.User" user "User.Comments")
		(21 "Eco1.User" user "User.Eco1")
		(23 "Eco2.User" user "User.Eco2")
		(25 "Edge.Cuts" user "Board Geometry/Outline")
		(27 "Margin" user)
		(31 "F.CrtYd" user "Package Geometry/Place Bound Top")
		(29 "B.CrtYd" user "Package Geometry/Place Bound Bottom")
		(35 "F.Fab" user "Ref Des/Assembly Top")
		(33 "B.Fab" user "Ref Des/Assembly Bottom")
	)
	(footprint ""
		(layer "B.Cu")
		(at 83.933538 -342.936576 90)
		(property "Reference" "PC492_P1_7"
			(at 0 0 90)
			(layer "B.SilkS")
			(hide yes)
			(effects
				(font
					(size 1.27 1.27)
				)
				(justify mirror)
			)
		)
		(property "Value" ""
			(at 0 0 90)
			(layer "B.Fab")
			(effects
				(font
					(size 1.27 1.27)
				)
				(justify mirror)
			)
		)
		(duplicate_pad_numbers_are_jumpers no)
		(fp_line
			(start 1.524 -0.762)
			(end -1.524 -0.762)
			(stroke
				(width 0.1524)
				(type default)
			)
			(layer "B.SilkS")
		)
		(fp_line
			(start -1.524 -0.762)
			(end -1.524 0.762)
			(stroke
				(width 0.1524)
				(type default)
			)
			(layer "B.SilkS")
		)
		(fp_line
			(start 1.524 0.762)
			(end 1.524 -0.762)
			(stroke
				(width 0.1524)
				(type default)
			)
			(layer "B.SilkS")
		)
		(fp_line
			(start -1.524 0.762)
			(end 1.524 0.762)
			(stroke
				(width 0.1524)
				(type default)
			)
			(layer "B.SilkS")
		)
		(fp_line
			(start 1.1049 -0.724916)
			(end 1.1049 0.724916)
			(stroke
				(width 0.1)
				(type default)
			)
			(layer "B.Fab")
		)
		(fp_line
			(start -1.1049 -0.724916)
			(end 1.1049 -0.724916)
			(stroke
				(width 0.1)
				(type default)
			)
			(layer "B.Fab")
		)
		(fp_line
			(start 1.1049 0.724916)
			(end -1.1049 0.724916)
			(stroke
				(width 0.1)
				(type default)
			)
			(layer "B.Fab")
		)
		(fp_line
			(start -1.1049 0.724916)
			(end -1.1049 -0.724916)
			(stroke
				(width 0.1)
				(type default)
			)
			(layer "B.Fab")
		)
		(pad "1" smd rect
			(at 0.889 0 90)
			(size 1.016 1.27)
			(layers "B.Cu" "B.Mask" "B.Paste")
			(net "SW_P12V_PVCCIN_CPU1_FLT")
		)
		(pad "2" smd rect
			(at -0.889 0 90)
			(size 1.016 1.27)
			(layers "B.Cu" "B.Mask" "B.Paste")
			(net "GND")
		)
	)
	(footprint ""
		(layer "B.Cu")
		(at 416.02914 -176.20107)
		(property "Reference" "PC196_P0_2"
			(at 0 0 0)
			(layer "B.SilkS")
			(hide yes)
			(effects
				(font
					(size 1.27 1.27)
				)
				(justify mirror)
			)
		)
		(property "Value" ""
			(at 0 0 0)
			(layer "B.Fab")
			(effects
				(font
					(size 1.27 1.27)
				)
				(justify mirror)
			)
		)
		(duplicate_pad_numbers_are_jumpers no)
		(fp_line
			(start -1.524 -0.762)
			(end -1.524 0.762)
			(stroke
				(width 0.1524)
				(type default)
			)
			(layer "B.SilkS")
		)
		(fp_line
			(start -1.524 0.762)
			(end 1.524 0.762)
			(stroke
				(width 0.1524)
				(type default)
			)
			(layer "B.SilkS")
		)
		(fp_line
			(start 1.524 -0.762)
			(end -1.524 -0.762)
			(stroke
				(width 0.1524)
				(type default)
			)
			(layer "B.SilkS")
		)
		(fp_line
			(start 1.524 0.762)
			(end 1.524 -0.762)
			(stroke
				(width 0.1524)
				(type default)
			)
			(layer "B.SilkS")
		)
		(fp_line
			(start -1.1049 -0.724916)
			(end 1.1049 -0.724916)
			(stroke
				(width 0.1)
				(type default)
			)
			(layer "B.Fab")
		)
		(fp_line
			(start -1.1049 0.724916)
			(end -1.1049 -0.724916)
			(stroke
				(width 0.1)
				(type default)
			)
			(layer "B.Fab")
		)
		(fp_line
			(start 1.1049 -0.724916)
			(end 1.1049 0.724916)
			(stroke
				(width 0.1)
				(type default)
			)
			(layer "B.Fab")
		)
		(fp_line
			(start 1.1049 0.724916)
			(end -1.1049 0.724916)
			(stroke
				(width 0.1)
				(type default)
			)
			(layer "B.Fab")
		)
		(pad "1" smd rect
			(at 0.889 0)
			(size 1.016 1.27)
			(layers "B.Cu" "B.Mask" "B.Paste")
			(net "SW_P12V_PVCCINFAON_CPU0_FLT")
		)
		(pad "2" smd rect
			(at -0.889 0)
			(size 1.016 1.27)
			(layers "B.Cu" "B.Mask" "B.Paste")
			(net "GND")
		)
	)
	(footprint ""
		(layer "B.Cu")
		(at 337.89874 -337.145884 90)
		(property "Reference" "PC262_P0_6"
			(at 0 0 90)
			(layer "B.SilkS")
			(hide yes)
			(effects
				(font
					(size 1.27 1.27)
				)
				(justify mirror)
			)
		)
		(property "Value" ""
			(at 0 0 90)
			(layer "B.Fab")
			(effects
				(font
					(size 1.27 1.27)
				)
				(justify mirror)
			)
		)
		(duplicate_pad_numbers_are_jumpers no)
		(fp_line
			(start 1.524 -0.762)
			(end -1.524 -0.762)
			(stroke
				(width 0.1524)
				(type default)
			)
			(layer "B.SilkS")
		)
		(fp_line
			(start -1.524 -0.762)
			(end -1.524 0.762)
			(stroke
				(width 0.1524)
				(type default)
			)
			(layer "B.SilkS")
		)
		(fp_line
			(start 1.524 0.762)
			(end 1.524 -0.762)
			(stroke
				(width 0.1524)
				(type default)
			)
			(layer "B.SilkS")
		)
		(fp_line
			(start -1.524 0.762)
			(end 1.524 0.762)
			(stroke
				(width 0.1524)
				(type default)
			)
			(layer "B.SilkS")
		)
		(fp_line
			(start 1.1049 -0.724916)
			(end 1.1049 0.724916)
			(stroke
				(width 0.1)
				(type default)
			)
			(layer "B.Fab")
		)
		(fp_line
			(start -1.1049 -0.724916)
			(end 1.1049 -0.724916)
			(stroke
				(width 0.1)
				(type default)
			)
			(layer "B.Fab")
		)
		(fp_line
			(start 1.1049 0.724916)
			(end -1.1049 0.724916)
			(stroke
				(width 0.1)
				(type default)
			)
			(layer "B.Fab")
		)
		(fp_line
			(start -1.1049 0.724916)
			(end -1.1049 -0.724916)
			(stroke
				(width 0.1)
				(type default)
			)
			(layer "B.Fab")
		)
		(pad "1" smd rect
			(at 0.889 0 90)
			(size 1.016 1.27)
			(layers "B.Cu" "B.Mask" "B.Paste")
			(net "SW_P12V_PVCCIN_CPU0_FLT")
		)
		(pad "2" smd rect
			(at -0.889 0 90)
			(size 1.016 1.27)
			(layers "B.Cu" "B.Mask" "B.Paste")
			(net "GND")
		)
	)
	(footprint ""
		(layer "B.Cu")
		(at 181.457346 -319.268856 180)
		(property "Reference" "C87"
			(at 0 0 0)
			(layer "B.SilkS")
			(hide yes)
			(effects
				(font
					(size 1.27 1.27)
				)
				(justify mirror)
			)
		)
		(property "Value" ""
			(at 0 0 0)
			(layer "B.Fab")
			(effects
				(font
					(size 1.27 1.27)
				)
				(justify mirror)
			)
		)
		(duplicate_pad_numbers_are_jumpers no)
		(fp_line
			(start 0.7874 0.4064)
			(end 0.7874 -0.4064)
			(stroke
				(width 0.1524)
				(type default)
			)
			(layer "B.SilkS")
		)
		(fp_line
			(start 0.7874 -0.4064)
			(end -0.7874 -0.4064)
			(stroke
				(width 0.1524)
				(type default)
			)
			(layer "B.SilkS")
		)
		(fp_line
			(start -0.7874 0.4064)
			(end 0.7874 0.4064)
			(stroke
				(width 0.1524)
				(type default)
			)
			(layer "B.SilkS")
		)
		(fp_line
			(start -0.7874 -0.4064)
			(end -0.7874 0.4064)
			(stroke
				(width 0.1524)
				(type default)
			)
			(layer "B.SilkS")
		)
		(fp_line
			(start 0.67945 0.3048)
			(end 0.67945 -0.305054)
			(stroke
				(width 0.1)
				(type default)
			)
			(layer "B.Fab")
		)
		(fp_line
			(start 0.67945 -0.305054)
			(end 0.12065 -0.305054)
			(stroke
				(width 0.1)
				(type default)
			)
			(layer "B.Fab")
		)
		(fp_line
			(start 0.12065 0.3048)
			(end 0.67945 0.3048)
			(stroke
				(width 0.1)
				(type default)
			)
			(layer "B.Fab")
		)
		(fp_line
			(start 0.12065 0.2794)
			(end 0.12065 0.3048)
			(stroke
				(width 0.1)
				(type default)
			)
			(layer "B.Fab")
		)
		(fp_line
			(start 0.12065 -0.2794)
			(end -0.12065 -0.2794)
			(stroke
				(width 0.1)
				(type default)
			)
			(layer "B.Fab")
		)
		(fp_line
			(start 0.12065 -0.305054)
			(end 0.12065 -0.2794)
			(stroke
				(width 0.1)
				(type default)
			)
			(layer "B.Fab")
		)
		(fp_line
			(start -0.120396 0.3048)
			(end -0.120396 0.2794)
			(stroke
				(width 0.1)
				(type default)
			)
			(layer "B.Fab")
		)
		(fp_line
			(start -0.120396 0.2794)
			(end 0.12065 0.2794)
			(stroke
				(width 0.1)
				(type default)
			)
			(layer "B.Fab")
		)
		(fp_line
			(start -0.12065 -0.2794)
			(end -0.12065 -0.3048)
			(stroke
				(width 0.1)
				(type default)
			)
			(layer "B.Fab")
		)
		(fp_line
			(start -0.12065 -0.3048)
			(end -0.67945 -0.3048)
			(stroke
				(width 0.1)
				(type default)
			)
			(layer "B.Fab")
		)
		(fp_line
			(start -0.67945 0.3048)
			(end -0.120396 0.3048)
			(stroke
				(width 0.1)
				(type default)
			)
			(layer "B.Fab")
		)
		(fp_line
			(start -0.67945 -0.3048)
			(end -0.67945 0.3048)
			(stroke
				(width 0.1)
				(type default)
			)
			(layer "B.Fab")
		)
		(pad "1" smd circle
			(at 0.40005 0)
			(size 0 0)
			(layers "B.Cu" "B.Mask" "B.Paste")
			(net "P3V3_AUX")
		)
		(pad "2" smd circle
			(at -0.40005 0)
			(size 0 0)
			(layers "B.Cu" "B.Mask" "B.Paste")
			(net "GND")
		)
	)
	(footprint ""
		(layer "B.Cu")
		(at 409.284932 -162.185858 180)
		(property "Reference" "PC1910"
			(at 0 0 0)
			(layer "B.SilkS")
			(hide yes)
			(effects
				(font
					(size 1.27 1.27)
				)
				(justify mirror)
			)
		)
		(property "Value" ""
			(at 0 0 0)
			(layer "B.Fab")
			(effects
				(font
					(size 1.27 1.27)
				)
				(justify mirror)
			)
		)
		(duplicate_pad_numbers_are_jumpers no)
		(fp_line
			(start 4.84378 -2.150618)
			(end 4.842256 2.163064)
			(stroke
				(width 0.1524)
				(type default)
			)
			(layer "B.SilkS")
		)
		(fp_line
			(start 4.84378 -2.150618)
			(end 4.53898 -2.150618)
			(stroke
				(width 0.1524)
				(type default)
			)
			(layer "B.SilkS")
		)
		(fp_line
			(start 4.83108 2.150364)
			(end 4.447794 2.149348)
			(stroke
				(width 0.1524)
				(type default)
			)
			(layer "B.SilkS")
		)
		(fp_line
			(start 4.69138 -2.150618)
			(end 4.692396 2.161032)
			(stroke
				(width 0.1524)
				(type default)
			)
			(layer "B.SilkS")
		)
		(fp_line
			(start 4.53898 2.15011)
			(end 4.53898 -2.15011)
			(stroke
				(width 0.1524)
				(type default)
			)
			(layer "B.SilkS")
		)
		(fp_line
			(start 4.53898 -2.15011)
			(end -4.53898 -2.15011)
			(stroke
				(width 0.1524)
				(type default)
			)
			(layer "B.SilkS")
		)
		(fp_line
			(start 4.53898 -2.150618)
			(end 4.539742 2.152142)
			(stroke
				(width 0.1524)
				(type default)
			)
			(layer "B.SilkS")
		)
		(fp_line
			(start -4.53898 2.15011)
			(end 4.53898 2.15011)
			(stroke
				(width 0.1524)
				(type default)
			)
			(layer "B.SilkS")
		)
		(fp_line
			(start -4.53898 -2.15011)
			(end -4.53898 2.15011)
			(stroke
				(width 0.1524)
				(type default)
			)
			(layer "B.SilkS")
		)
		(fp_line
			(start 3.64998 2.15011)
			(end 3.64998 -2.15011)
			(stroke
				(width 0.1)
				(type default)
			)
			(layer "B.Fab")
		)
		(fp_line
			(start 3.64998 -2.15011)
			(end -3.64998 -2.15011)
			(stroke
				(width 0.1)
				(type default)
			)
			(layer "B.Fab")
		)
		(fp_line
			(start -3.64998 2.15011)
			(end 3.64998 2.15011)
			(stroke
				(width 0.1)
				(type default)
			)
			(layer "B.Fab")
		)
		(fp_line
			(start -3.64998 -2.15011)
			(end -3.64998 2.15011)
			(stroke
				(width 0.1)
				(type default)
			)
			(layer "B.Fab")
		)
		(fp_text user "+"
			(at 6.214872 -0.337058 180)
			(unlocked yes)
			(layer "B.SilkS")
			(effects
				(font
					(size 1.905 1.4224)
					(thickness 0.1524)
				)
				(justify left mirror)
			)
		)
		(fp_text user "-"
			(at -5.646928 0.98552 180)
			(unlocked yes)
			(layer "B.SilkS")
			(effects
				(font
					(size 1.905 1.4224)
					(thickness 0.1524)
				)
				(justify left mirror)
			)
		)
		(fp_text user "+"
			(at 6.214872 -0.337058 180)
			(unlocked yes)
			(layer "B.Fab")
			(effects
				(font
					(size 1.905 1.4224)
					(thickness 0.1524)
				)
				(justify left mirror)
			)
		)
		(fp_text user "-"
			(at -4.313174 -0.094488 180)
			(unlocked yes)
			(layer "B.Fab")
			(effects
				(font
					(size 1.905 1.4224)
					(thickness 0.1524)
				)
				(justify left mirror)
			)
		)
		(pad "1" smd rect
			(at 3.199892 0)
			(size 2.413 2.8194)
			(layers "B.Cu" "B.Mask" "B.Paste")
			(net "PVCCD_HV_CPU0")
		)
		(pad "2" smd rect
			(at -3.199892 0)
			(size 2.413 2.8194)
			(layers "B.Cu" "B.Mask" "B.Paste")
			(net "GND")
		)
	)
	(footprint ""
		(layer "B.Cu")
		(at 175.31588 -13.762228 -90)
		(property "Reference" "R1336"
			(at 0 0 90)
			(layer "B.SilkS")
			(hide yes)
			(effects
				(font
					(size 1.27 1.27)
				)
				(justify mirror)
			)
		)
		(property "Value" ""
			(at 0 0 90)
			(layer "B.Fab")
			(effects
				(font
					(size 1.27 1.27)
				)
				(justify mirror)
			)
		)
		(duplicate_pad_numbers_are_jumpers no)
		(fp_line
			(start -0.7874 0.4064)
			(end 0.7874 0.4064)
			(stroke
				(width 0.1524)
				(type default)
			)
			(layer "B.SilkS")
		)
		(fp_line
			(start 0.7874 0.4064)
			(end 0.7874 -0.4064)
			(stroke
				(width 0.1524)
				(type default)
			)
			(layer "B.SilkS")
		)
		(fp_line
			(start -0.7874 -0.4064)
			(end -0.7874 0.4064)
			(stroke
				(width 0.1524)
				(type default)
			)
			(layer "B.SilkS")
		)
		(fp_line
			(start 0.7874 -0.4064)
			(end -0.7874 -0.4064)
			(stroke
				(width 0.1524)
				(type default)
			)
			(layer "B.SilkS")
		)
		(fp_line
			(start -0.67945 0.3048)
			(end -0.120396 0.3048)
			(stroke
				(width 0.1)
				(type default)
			)
			(layer "B.Fab")
		)
		(fp_line
			(start -0.120396 0.3048)
			(end -0.120396 0.2794)
			(stroke
				(width 0.1)
				(type default)
			)
			(layer "B.Fab")
		)
		(fp_line
			(start 0.12065 0.3048)
			(end 0.67945 0.3048)
			(stroke
				(width 0.1)
				(type default)
			)
			(layer "B.Fab")
		)
		(fp_line
			(start 0.67945 0.3048)
			(end 0.67945 -0.305054)
			(stroke
				(width 0.1)
				(type default)
			)
			(layer "B.Fab")
		)
		(fp_line
			(start -0.120396 0.2794)
			(end 0.12065 0.2794)
			(stroke
				(width 0.1)
				(type default)
			)
			(layer "B.Fab")
		)
		(fp_line
			(start 0.12065 0.2794)
			(end 0.12065 0.3048)
			(stroke
				(width 0.1)
				(type default)
			)
			(layer "B.Fab")
		)
		(fp_line
			(start -0.12065 -0.2794)
			(end -0.12065 -0.3048)
			(stroke
				(width 0.1)
				(type default)
			)
			(layer "B.Fab")
		)
		(fp_line
			(start 0.12065 -0.2794)
			(end -0.12065 -0.2794)
			(stroke
				(width 0.1)
				(type default)
			)
			(layer "B.Fab")
		)
		(fp_line
			(start -0.67945 -0.3048)
			(end -0.67945 0.3048)
			(stroke
				(width 0.1)
				(type default)
			)
			(layer "B.Fab")
		)
		(fp_line
			(start -0.12065 -0.3048)
			(end -0.67945 -0.3048)
			(stroke
				(width 0.1)
				(type default)
			)
			(layer "B.Fab")
		)
		(fp_line
			(start 0.12065 -0.305054)
			(end 0.12065 -0.2794)
			(stroke
				(width 0.1)
				(type default)
			)
			(layer "B.Fab")
		)
		(fp_line
			(start 0.67945 -0.305054)
			(end 0.12065 -0.305054)
			(stroke
				(width 0.1)
				(type default)
			)
			(layer "B.Fab")
		)
		(pad "1" smd circle
			(at 0.40005 0 90)
			(size 0 0)
			(layers "B.Cu" "B.Mask" "B.Paste")
			(net "I3C_BMC_SWB_SCL")
		)
		(pad "2" smd circle
			(at -0.40005 0 90)
			(size 0 0)
			(layers "B.Cu" "B.Mask" "B.Paste")
			(net "P3V3_AUX")
		)
	)
	(footprint ""
		(layer "B.Cu")
		(at 107.457494 -255.8542 -90)
		(property "Reference" "C324"
			(at 0 0 90)
			(layer "B.SilkS")
			(hide yes)
			(effects
				(font
					(size 1.27 1.27)
				)
				(justify mirror)
			)
		)
		(property "Value" ""
			(at 0 0 90)
			(layer "B.Fab")
			(effects
				(font
					(size 1.27 1.27)
				)
				(justify mirror)
			)
		)
		(duplicate_pad_numbers_are_jumpers no)
		(fp_line
			(start -1.524 0.762)
			(end 1.524 0.762)
			(stroke
				(width 0.1524)
				(type default)
			)
			(layer "B.SilkS")
		)
		(fp_line
			(start 1.524 0.762)
			(end 1.524 -0.762)
			(stroke
				(width 0.1524)
				(type default)
			)
			(layer "B.SilkS")
		)
		(fp_line
			(start -1.524 -0.762)
			(end -1.524 0.762)
			(stroke
				(width 0.1524)
				(type default)
			)
			(layer "B.SilkS")
		)
		(fp_line
			(start 1.524 -0.762)
			(end -1.524 -0.762)
			(stroke
				(width 0.1524)
				(type default)
			)
			(layer "B.SilkS")
		)
		(fp_line
			(start -1.1049 0.724916)
			(end -1.1049 -0.724916)
			(stroke
				(width 0.1)
				(type default)
			)
			(layer "B.Fab")
		)
		(fp_line
			(start 1.1049 0.724916)
			(end -1.1049 0.724916)
			(stroke
				(width 0.1)
				(type default)
			)
			(layer "B.Fab")
		)
		(fp_line
			(start -1.1049 -0.724916)
			(end 1.1049 -0.724916)
			(stroke
				(width 0.1)
				(type default)
			)
			(layer "B.Fab")
		)
		(fp_line
			(start 1.1049 -0.724916)
			(end 1.1049 0.724916)
			(stroke
				(width 0.1)
				(type default)
			)
			(layer "B.Fab")
		)
		(pad "1" smd rect
			(at 0.889 0 270)
			(size 1.016 1.27)
			(layers "B.Cu" "B.Mask" "B.Paste")
			(net "PVCCIN_CPU1")
		)
		(pad "2" smd rect
			(at -0.889 0 270)
			(size 1.016 1.27)
			(layers "B.Cu" "B.Mask" "B.Paste")
			(net "GND")
		)
	)
)
